# T6G (Grand Teton) — schematic netlist excerpt (pin names and nets, part order shuffled) for the footprints in the layout excerpt that follows; sources: Cadence DE-HDL packaged netlist, KiCad conversion of 04192023_DAF0TMB3IC0_F0TG_MB_C_brd_V02_OCP.brd

C2593  Q_CAP  22UF 4V 20% X6S  pkg C0402  page 70 : A = PVDDCR_SOC_P0 ; B = GND
C287  Q_CAP  0.1UF 10V 10% X7S  pkg C0201  page 334 : A = P1V8_CPU1_RT1_1A ; B = GND
C488  Q_CAP  1UF 4V 20% X6S  pkg 0201  page 356 : A = P0V9_CPU1_RT3_2A ; B = GND

(kicad_pcb
	(version 20260206)
	(generator "pcbnew")
	(generator_version "10.0")
	(general
		(thickness 1.6)
		(legacy_teardrops no)
	)
	(paper "A4")
	(title_block
		(title "04192023_DAF0TMB3IC0_F0TG_MB_C_brd_V02_OCP.brd")
		(comment 1 "Grand Teton / footprints 5055-5057 of 8354")
	)
	(layers
		(0 "F.Cu" signal "TOP")
		(4 "In1.Cu" signal "GND")
		(6 "In2.Cu" signal "IN1")
		(8 "In3.Cu" signal "GND1")
		(10 "In4.Cu" signal "IN2")
		(12 "In5.Cu" signal "GND2")
		(14 "In6.Cu" signal "IN3")
		(16 "In7.Cu" signal "GND3")
		(18 "In8.Cu" signal "VCC")
		(20 "In9.Cu" signal "VCC1")
		(22 "In10.Cu" signal "GND4")
		(24 "In11.Cu" signal "IN4")
		(26 "In12.Cu" signal "GND5")
		(28 "In13.Cu" signal "IN5")
		(30 "In14.Cu" signal "GND6")
		(32 "In15.Cu" signal "IN6")
		(34 "In16.Cu" signal "GND7")
		(2 "B.Cu" signal "BOTTOM")
		(9 "F.Adhes" user "F.Adhesive")
		(11 "B.Adhes" user "B.Adhesive")
		(13 "F.Paste" user "Package Geometry/Pastemask Top")
		(15 "B.Paste" user "Package Geometry/Pastemask Bottom")
		(5 "F.SilkS" user "Ref Des/Silkscreen Top")
		(7 "B.SilkS" user "Ref Des/Silkscreen Bottom")
		(1 "F.Mask" user "Board Geometry/Soldermask Top")
		(3 "B.Mask" user "Board Geometry/Soldermask Bottom")
		(17 "Dwgs.User" user "User.Drawings")
		(19 "Cmts.User" user "User.Comments")
		(21 "Eco1.User" user "User.Eco1")
		(23 "Eco2.User" user "User.Eco2")
		(25 "Edge.Cuts" user "Board Geometry/Outline")
		(27 "Margin" user)
		(31 "F.CrtYd" user "Package Geometry/Place Bound Top")
		(29 "B.CrtYd" user "Package Geometry/Place Bound Bottom")
		(35 "F.Fab" user "Ref Des/Assembly Top")
		(33 "B.Fab" user "Ref Des/Assembly Bottom")
	)
	(footprint ""
		(layer "B.Cu")
		(at 89.646252 -388.011162 -90)
		(property "Reference" "C287"
			(at 0 0 90)
			(layer "B.SilkS")
			(hide yes)
			(effects
				(font
					(size 1.27 1.27)
				)
				(justify mirror)
			)
		)
		(property "Value" ""
			(at 0 0 90)
			(layer "B.Fab")
			(effects
				(font
					(size 1.27 1.27)
				)
				(justify mirror)
			)
		)
		(duplicate_pad_numbers_are_jumpers no)
		(fp_line
			(start -0.299974 0.150114)
			(end 0.299974 0.150114)
			(stroke
				(width 0.1)
				(type default)
			)
			(layer "B.Fab")
		)
		(fp_line
			(start 0.299974 0.150114)
			(end 0.299974 -0.150114)
			(stroke
				(width 0.1)
				(type default)
			)
			(layer "B.Fab")
		)
		(fp_line
			(start -0.299974 -0.150114)
			(end -0.299974 0.150114)
			(stroke
				(width 0.1)
				(type default)
			)
			(layer "B.Fab")
		)
		(fp_line
			(start 0.299974 -0.150114)
			(end -0.299974 -0.150114)
			(stroke
				(width 0.1)
				(type default)
			)
			(layer "B.Fab")
		)
		(pad "1" smd rect
			(at 0.2667 0 90)
			(size 0.3048 0.381)
			(layers "B.Cu" "B.Mask" "B.Paste")
			(net "P1V8_CPU1_RT1_1A")
		)
		(pad "2" smd rect
			(at -0.2667 0 90)
			(size 0.3048 0.381)
			(layers "B.Cu" "B.Mask" "B.Paste")
			(net "GND")
		)
	)
	(footprint ""
		(layer "B.Cu")
		(at 357.835454 -251.78131)
		(property "Reference" "C2593"
			(at 0 0 0)
			(layer "B.SilkS")
			(hide yes)
			(effects
				(font
					(size 1.27 1.27)
				)
				(justify mirror)
			)
		)
		(property "Value" ""
			(at 0 0 0)
			(layer "B.Fab")
			(effects
				(font
					(size 1.27 1.27)
				)
				(justify mirror)
			)
		)
		(duplicate_pad_numbers_are_jumpers no)
		(fp_line
			(start -0.7874 -0.4064)
			(end -0.7874 0.4064)
			(stroke
				(width 0.1524)
				(type default)
			)
			(layer "B.SilkS")
		)
		(fp_line
			(start -0.7874 0.4064)
			(end 0.7874 0.4064)
			(stroke
				(width 0.1524)
				(type default)
			)
			(layer "B.SilkS")
		)
		(fp_line
			(start 0.7874 -0.4064)
			(end -0.7874 -0.4064)
			(stroke
				(width 0.1524)
				(type default)
			)
			(layer "B.SilkS")
		)
		(fp_line
			(start 0.7874 0.4064)
			(end 0.7874 -0.4064)
			(stroke
				(width 0.1524)
				(type default)
			)
			(layer "B.SilkS")
		)
		(fp_line
			(start -0.67945 -0.3048)
			(end -0.67945 0.3048)
			(stroke
				(width 0.1)
				(type default)
			)
			(layer "B.Fab")
		)
		(fp_line
			(start -0.67945 0.3048)
			(end -0.120396 0.3048)
			(stroke
				(width 0.1)
				(type default)
			)
			(layer "B.Fab")
		)
		(fp_line
			(start -0.12065 -0.3048)
			(end -0.67945 -0.3048)
			(stroke
				(width 0.1)
				(type default)
			)
			(layer "B.Fab")
		)
		(fp_line
			(start -0.12065 -0.2794)
			(end -0.12065 -0.3048)
			(stroke
				(width 0.1)
				(type default)
			)
			(layer "B.Fab")
		)
		(fp_line
			(start -0.120396 0.2794)
			(end 0.12065 0.2794)
			(stroke
				(width 0.1)
				(type default)
			)
			(layer "B.Fab")
		)
		(fp_line
			(start -0.120396 0.3048)
			(end -0.120396 0.2794)
			(stroke
				(width 0.1)
				(type default)
			)
			(layer "B.Fab")
		)
		(fp_line
			(start 0.12065 -0.305054)
			(end 0.12065 -0.2794)
			(stroke
				(width 0.1)
				(type default)
			)
			(layer "B.Fab")
		)
		(fp_line
			(start 0.12065 -0.2794)
			(end -0.12065 -0.2794)
			(stroke
				(width 0.1)
				(type default)
			)
			(layer "B.Fab")
		)
		(fp_line
			(start 0.12065 0.2794)
			(end 0.12065 0.3048)
			(stroke
				(width 0.1)
				(type default)
			)
			(layer "B.Fab")
		)
		(fp_line
			(start 0.12065 0.3048)
			(end 0.67945 0.3048)
			(stroke
				(width 0.1)
				(type default)
			)
			(layer "B.Fab")
		)
		(fp_line
			(start 0.67945 -0.305054)
			(end 0.12065 -0.305054)
			(stroke
				(width 0.1)
				(type default)
			)
			(layer "B.Fab")
		)
		(fp_line
			(start 0.67945 0.3048)
			(end 0.67945 -0.305054)
			(stroke
				(width 0.1)
				(type default)
			)
			(layer "B.Fab")
		)
		(pad "1" smd circle
			(at 0.40005 0 180)
			(size 0 0)
			(layers "B.Cu" "B.Mask" "B.Paste")
			(net "PVDDCR_SOC_P0")
		)
		(pad "2" smd circle
			(at -0.40005 0 180)
			(size 0 0)
			(layers "B.Cu" "B.Mask" "B.Paste")
			(net "GND")
		)
	)
	(footprint ""
		(layer "B.Cu")
		(at 112.518444 -387.05028)
		(property "Reference" "C488"
			(at 0 0 0)
			(layer "B.SilkS")
			(hide yes)
			(effects
				(font
					(size 1.27 1.27)
				)
				(justify mirror)
			)
		)
		(property "Value" ""
			(at 0 0 0)
			(layer "B.Fab")
			(effects
				(font
					(size 1.27 1.27)
				)
				(justify mirror)
			)
		)
		(duplicate_pad_numbers_are_jumpers no)
		(fp_line
			(start -0.299974 -0.150114)
			(end -0.299974 0.150114)
			(stroke
				(width 0.1)
				(type default)
			)
			(layer "B.Fab")
		)
		(fp_line
			(start -0.299974 0.150114)
			(end 0.299974 0.150114)
			(stroke
				(width 0.1)
				(type default)
			)
			(layer "B.Fab")
		)
		(fp_line
			(start 0.299974 -0.150114)
			(end -0.299974 -0.150114)
			(stroke
				(width 0.1)
				(type default)
			)
			(layer "B.Fab")
		)
		(fp_line
			(start 0.299974 0.150114)
			(end 0.299974 -0.150114)
			(stroke
				(width 0.1)
				(type default)
			)
			(layer "B.Fab")
		)
		(pad "1" smd rect
			(at 0.2667 0 180)
			(size 0.3048 0.381)
			(layers "B.Cu" "B.Mask" "B.Paste")
			(net "P0V9_CPU1_RT3_2A")
		)
		(pad "2" smd rect
			(at -0.2667 0 180)
			(size 0.3048 0.381)
			(layers "B.Cu" "B.Mask" "B.Paste")
			(net "GND")
		)
	)
)
